(kicad_pcb
	(version 20241229)
	(generator "pcbnew")
	(generator_version "9.0")
	(general
		(thickness 1.294)
		(legacy_teardrops no)
	)
	(paper "A3")
	(title_block
		(title "Kintex 410T devboard")
		(date "2024-04-03")
		(rev "1.1.2")
		(comment 9 "footprints 111-115 of 975")
	)
	(layers
		(0 "F.Cu" mixed)
		(4 "In1.Cu" power)
		(6 "In2.Cu" power)
		(8 "In3.Cu" mixed)
		(10 "In4.Cu" power)
		(12 "In5.Cu" mixed)
		(14 "In6.Cu" power)
		(16 "In7.Cu" mixed)
		(18 "In8.Cu" power)
		(2 "B.Cu" mixed)
		(9 "F.Adhes" user "F.Adhesive")
		(11 "B.Adhes" user "B.Adhesive")
		(13 "F.Paste" user)
		(15 "B.Paste" user)
		(5 "F.SilkS" user "F.Silkscreen")
		(7 "B.SilkS" user "B.Silkscreen")
		(1 "F.Mask" user)
		(3 "B.Mask" user)
		(17 "Dwgs.User" user "User.Drawings")
		(19 "Cmts.User" user "User.Comments")
		(21 "Eco1.User" user "User.Eco1")
		(23 "Eco2.User" user "User.Eco2")
		(25 "Edge.Cuts" user)
		(27 "Margin" user)
		(31 "F.CrtYd" user "F.Courtyard")
		(29 "B.CrtYd" user "B.Courtyard")
		(35 "F.Fab" user)
		(33 "B.Fab" user)
	)
	(footprint "antmicro-footprints:R_0402_1005Metric"
		(layer "F.Cu")
		(at 236 136.4)
		(descr "Resistor SMD 0402")
		(tags "resistor SMD 0402")
		(property "Reference" "R189"
			(at -1.625 -1.45 0)
			(layer "F.SilkS")
			(effects
				(font
					(size 0.7 0.7)
					(thickness 0.15)
				)
				(justify left bottom)
			)
		)
		(property "Value" "R_0R_0402"
			(at 0 1.4 0)
			(layer "F.Fab")
			(effects
				(font
					(size 0.7 0.7)
					(thickness 0.15)
				)
				(justify left bottom)
			)
		)
		(property "Description" "SMD Chip Resistor, Jumper, 0 ohm, 100 mW, 0402 [1005 Metric], Thick Film, General Purpose"
			(at 0 0 0)
			(layer "F.Fab")
			(hide yes)
			(effects
				(font
					(size 1.27 1.27)
					(thickness 0.15)
				)
			)
		)
		(property "Author" "Antmicro"
			(at 0 0 0)
			(layer "F.Fab")
			(hide yes)
			(effects
				(font
					(size 1 1)
					(thickness 0.15)
				)
			)
		)
		(property "Current" "1A"
			(at 0 0 0)
			(layer "F.Fab")
			(hide yes)
			(effects
				(font
					(size 1 1)
					(thickness 0.15)
				)
			)
		)
		(property "License" "Apache-2.0"
			(at 0 0 0)
			(layer "F.Fab")
			(hide yes)
			(effects
				(font
					(size 1 1)
					(thickness 0.15)
				)
			)
		)
		(property "MPN" "ERJ2GE0R00X"
			(at 0 0 0)
			(layer "F.Fab")
			(hide yes)
			(effects
				(font
					(size 1 1)
					(thickness 0.15)
				)
			)
		)
		(property "Manufacturer" "Panasonic"
			(at 0 0 0)
			(layer "F.Fab")
			(hide yes)
			(effects
				(font
					(size 1 1)
					(thickness 0.15)
				)
			)
		)
		(property "Tolerance" ""
			(at 0 0 0)
			(layer "F.Fab")
			(hide yes)
			(effects
				(font
					(size 1 1)
					(thickness 0.15)
				)
			)
		)
		(property "Val" "0R"
			(at 0 0 0)
			(layer "F.Fab")
			(hide yes)
			(effects
				(font
					(size 1 1)
					(thickness 0.15)
				)
			)
		)
		(sheetname "USB PHY")
		(sheetfile "usb-phy.kicad_sch")
		(attr smd)
		(fp_rect
			(start -0.925 -0.47)
			(end 0.925 0.47)
			(stroke
				(width 0.05)
				(type default)
			)
			(fill no)
			(layer "F.CrtYd")
		)
		(fp_rect
			(start -0.5 -0.25)
			(end 0.5 0.25)
			(stroke
				(width 0.15)
				(type solid)
			)
			(fill no)
			(layer "F.Fab")
		)
		(pad "1" smd roundrect
			(at -0.48 0)
			(size 0.59 0.64)
			(layers "F.Cu" "F.Mask" "F.Paste")
			(roundrect_rratio 0.25)
			(net 1336 "/I2C.SDA")
			(pintype "passive")
		)
		(pad "2" smd roundrect
			(at 0.48 0)
			(size 0.59 0.64)
			(layers "F.Cu" "F.Mask" "F.Paste")
			(roundrect_rratio 0.25)
			(net 942 "/USB PHY/FTDI_SDA_IN")
			(pintype "passive")
		)
	)
	(footprint "antmicro-footprints:C_0402_1005Metric"
		(layer "F.Cu")
		(at 203.653752 105.0365 180)
		(descr "Capacitor SMD 0402")
		(tags "capacitor SMD 0402")
		(property "Reference" "C263"
			(at -6.546248 -7.7635 0)
			(layer "F.SilkS")
			(effects
				(font
					(size 0.7 0.7)
					(thickness 0.15)
				)
				(justify right bottom)
			)
		)
		(property "Value" "C_22p_0402"
			(at 0 1.4 0)
			(layer "F.Fab")
			(effects
				(font
					(size 0.7 0.7)
					(thickness 0.15)
				)
				(justify right bottom)
			)
		)
		(property "Description" "SMD Multilayer Ceramic Capacitor, 22 pF, 50 V, 0402 [1005 Metric], ± 5%, C0G / NP0, CC Series"
			(at 0 0 180)
			(layer "F.Fab")
			(hide yes)
			(effects
				(font
					(size 1.27 1.27)
					(thickness 0.15)
				)
			)
		)
		(property "Author" "Antmicro"
			(at 407.307504 210.073 0)
			(layer "F.Fab")
			(hide yes)
			(effects
				(font
					(size 1 1)
					(thickness 0.15)
				)
			)
		)
		(property "Dielectric" ""
			(at 407.307504 210.073 0)
			(layer "F.Fab")
			(hide yes)
			(effects
				(font
					(size 1 1)
					(thickness 0.15)
				)
			)
		)
		(property "License" "Apache-2.0"
			(at 407.307504 210.073 0)
			(layer "F.Fab")
			(hide yes)
			(effects
				(font
					(size 1 1)
					(thickness 0.15)
				)
			)
		)
		(property "MPN" "CC0402JRNPO9BN220"
			(at 407.307504 210.073 0)
			(layer "F.Fab")
			(hide yes)
			(effects
				(font
					(size 1 1)
					(thickness 0.15)
				)
			)
		)
		(property "Manufacturer" "YAGEO"
			(at 407.307504 210.073 0)
			(layer "F.Fab")
			(hide yes)
			(effects
				(font
					(size 1 1)
					(thickness 0.15)
				)
			)
		)
		(property "Val" "22p"
			(at 407.307504 210.073 0)
			(layer "F.Fab")
			(hide yes)
			(effects
				(font
					(size 1 1)
					(thickness 0.15)
				)
			)
		)
		(property "Voltage" ""
			(at 407.307504 210.073 0)
			(layer "F.Fab")
			(hide yes)
			(effects
				(font
					(size 1 1)
					(thickness 0.15)
				)
			)
		)
		(sheetname "HDMI + Ethernet")
		(sheetfile "hdmi-ethernet.kicad_sch")
		(attr smd)
		(fp_rect
			(start -0.925 -0.47)
			(end 0.925 0.47)
			(stroke
				(width 0.05)
				(type default)
			)
			(fill no)
			(layer "F.CrtYd")
		)
		(fp_line
			(start 0.504 0.248)
			(end -0.494 0.248)
			(stroke
				(width 0.15)
				(type solid)
			)
			(layer "F.Fab")
		)
		(fp_line
			(start 0.504 -0.25)
			(end 0.504 0.248)
			(stroke
				(width 0.15)
				(type solid)
			)
			(layer "F.Fab")
		)
		(fp_line
			(start -0.494 0.248)
			(end -0.494 -0.25)
			(stroke
				(width 0.15)
				(type solid)
			)
			(layer "F.Fab")
		)
		(fp_line
			(start -0.494 -0.25)
			(end 0.504 -0.25)
			(stroke
				(width 0.15)
				(type solid)
			)
			(layer "F.Fab")
		)
		(pad "1" smd roundrect
			(at -0.48 0 180)
			(size 0.59 0.64)
			(layers "F.Cu" "F.Mask" "F.Paste")
			(roundrect_rratio 0.25)
			(net 1 "GND")
			(pintype "passive")
		)
		(pad "2" smd roundrect
			(at 0.48 0 180)
			(size 0.59 0.64)
			(layers "F.Cu" "F.Mask" "F.Paste")
			(roundrect_rratio 0.25)
			(net 720 "/HDMI + Ethernet/GBE_XO")
			(pintype "passive")
		)
	)
	(footprint "antmicro-footprints:Vishay_PowerPAK_1212-8_Single"
		(layer "F.Cu")
		(at 190.0675 172.399)
		(descr "PowerPAK 1212-8 Single")
		(tags "Vishay PowerPAK 1212-8 Single")
		(property "Reference" "Q6"
			(at 2.9325 1.901 90)
			(layer "F.SilkS")
			(effects
				(font
					(size 0.7 0.7)
					(thickness 0.15)
				)
				(justify left bottom)
			)
		)
		(property "Value" "SI7613DN-T1-GE3"
			(at -8 2.7 0)
			(layer "F.Fab")
			(effects
				(font
					(size 0.7 0.7)
					(thickness 0.15)
				)
				(justify left bottom)
			)
		)
		(property "Description" "Power MOSFET, P Channel, 20 V, 35 A, 0.0072 ohm, PowerPAK 1212, Surface Mount"
			(at 0 0 0)
			(layer "F.Fab")
			(hide yes)
			(effects
				(font
					(size 1.27 1.27)
					(thickness 0.15)
				)
			)
		)
		(property "Author" "Antmicro"
			(at 0 0 0)
			(layer "F.Fab")
			(hide yes)
			(effects
				(font
					(size 1 1)
					(thickness 0.15)
				)
			)
		)
		(property "License" "Apache-2.0"
			(at 0 0 0)
			(layer "F.Fab")
			(hide yes)
			(effects
				(font
					(size 1 1)
					(thickness 0.15)
				)
			)
		)
		(property "MPN" "SI7613DN-T1-GE3"
			(at 0 0 0)
			(layer "F.Fab")
			(hide yes)
			(effects
				(font
					(size 1 1)
					(thickness 0.15)
				)
			)
		)
		(property "Manufacturer" "Vishay"
			(at 0 0 0)
			(layer "F.Fab")
			(hide yes)
			(effects
				(font
					(size 1 1)
					(thickness 0.15)
				)
			)
		)
		(sheetname "Power supply")
		(sheetfile "power-supply.kicad_sch")
		(attr smd)
		(fp_line
			(start -1.651 -1.651)
			(end -1.651 -1.317)
			(stroke
				(width 0.15)
				(type solid)
			)
			(layer "F.SilkS")
		)
		(fp_line
			(start -1.651 -1.651)
			(end 1.648 -1.651)
			(stroke
				(width 0.15)
				(type solid)
			)
			(layer "F.SilkS")
		)
		(fp_line
			(start -1.635 1.3)
			(end -1.635 1.634)
			(stroke
				(width 0.15)
				(type solid)
			)
			(layer "F.SilkS")
		)
		(fp_line
			(start -1.635 1.634)
			(end 1.634 1.634)
			(stroke
				(width 0.15)
				(type solid)
			)
			(layer "F.SilkS")
		)
		(fp_line
			(start 1.634 1.3)
			(end 1.634 1.634)
			(stroke
				(width 0.15)
				(type solid)
			)
			(layer "F.SilkS")
		)
		(fp_line
			(start 1.648 -1.651)
			(end 1.648 -1.317)
			(stroke
				(width 0.15)
				(type solid)
			)
			(layer "F.SilkS")
		)
		(fp_circle
			(center -1.9 -1.4)
			(end -1.85 -1.4)
			(stroke
				(width 0.15)
				(type solid)
			)
			(fill yes)
			(layer "F.SilkS")
		)
		(fp_rect
			(start -2 -1.8)
			(end 2 1.798)
			(stroke
				(width 0.05)
				(type solid)
			)
			(fill no)
			(layer "F.CrtYd")
		)
		(fp_line
			(start -1.6425 -1.4175)
			(end -1.4175 -1.6425)
			(stroke
				(width 0.15)
				(type solid)
			)
			(layer "F.Fab")
		)
		(fp_rect
			(start -1.651 -1.651)
			(end 1.648 1.648)
			(stroke
				(width 0.15)
				(type solid)
			)
			(fill no)
			(layer "F.Fab")
		)
		(pad "1" smd rect
			(at -1.436 -0.99)
			(size 0.99 0.405)
			(layers "F.Cu" "F.Mask" "F.Paste")
			(net 702 "VDC")
			(pinfunction "S")
			(pintype "passive")
		)
		(pad "2" smd rect
			(at -1.436 -0.332)
			(size 0.99 0.405)
			(layers "F.Cu" "F.Mask" "F.Paste")
			(net 702 "VDC")
			(pinfunction "S")
			(pintype "passive")
		)
		(pad "3" smd rect
			(at -1.436 0.33)
			(size 0.99 0.405)
			(layers "F.Cu" "F.Mask" "F.Paste")
			(net 702 "VDC")
			(pinfunction "S")
			(pintype "passive")
		)
		(pad "4" smd rect
			(at -1.436 0.988)
			(size 0.99 0.405)
			(layers "F.Cu" "F.Mask" "F.Paste")
			(net 341 "Net-(Q6-G)")
			(pinfunction "G")
			(pintype "passive")
		)
		(pad "5" smd custom
			(at 0.557 0)
			(size 1.725 2.235)
			(layers "F.Cu" "F.Mask" "F.Paste")
			(net 700 "/Power supply/USB_PD_VBUS")
			(pinfunction "D")
			(pintype "passive")
			(zone_connect 2)
			(options
				(clearance outline)
				(anchor rect)
			)
			(primitives
				(gr_poly
					(pts
						(xy 0.8625 0.1275) (xy 0.8625 -0.1275) (xy 1.3725 -0.1275) (xy 1.3725 -0.5325) (xy 0.8625 -0.5325)
						(xy 0.8625 -0.7875) (xy 1.3725 -0.7875) (xy 1.3725 -1.195) (xy 0.6125 -1.195) (xy 0.6125 1.195)
						(xy 1.3725 1.195) (xy 1.3725 0.7875) (xy 0.8625 0.7875) (xy 0.8625 0.5325) (xy 1.3725 0.5325)
						(xy 1.3725 0.1275)
					)
					(width 0)
					(fill yes)
				)
			)
		)
	)
	(footprint "antmicro-footprints:SOT-23-6"
		(layer "F.Cu")
		(at 189.089 176.147 90)
		(property "Reference" "U11"
			(at 1.197 -3.939 180)
			(layer "F.SilkS")
			(effects
				(font
					(size 0.7 0.7)
					(thickness 0.15)
				)
				(justify left bottom)
			)
		)
		(property "Value" "LTC4412IS6"
			(at -1.75 2.75 90)
			(layer "F.Fab")
			(effects
				(font
					(size 0.7 0.7)
					(thickness 0.15)
				)
				(justify left bottom)
			)
		)
		(property "Description" "Ideal diode controller"
			(at 0 0 90)
			(layer "F.Fab")
			(hide yes)
			(effects
				(font
					(size 1.27 1.27)
					(thickness 0.15)
				)
			)
		)
		(property "Author" "Antmicro"
			(at 365.236 -12.942 0)
			(layer "F.Fab")
			(hide yes)
			(effects
				(font
					(size 1 1)
					(thickness 0.15)
				)
			)
		)
		(property "License" "Apache-2.0"
			(at 365.236 -12.942 0)
			(layer "F.Fab")
			(hide yes)
			(effects
				(font
					(size 1 1)
					(thickness 0.15)
				)
			)
		)
		(property "MPN" "LTC4412IS6#TRMPBF"
			(at 365.236 -12.942 0)
			(layer "F.Fab")
			(hide yes)
			(effects
				(font
					(size 1 1)
					(thickness 0.15)
				)
			)
		)
		(property "Manufacturer" "Analog Devices"
			(at 365.236 -12.942 0)
			(layer "F.Fab")
			(hide yes)
			(effects
				(font
					(size 1 1)
					(thickness 0.15)
				)
			)
		)
		(sheetname "Power supply")
		(sheetfile "power-supply.kicad_sch")
		(attr smd)
		(fp_line
			(start 1.45 -0.7)
			(end 1.45 -0.4)
			(stroke
				(width 0.12)
				(type solid)
			)
			(layer "F.SilkS")
		)
		(fp_line
			(start 1.3 -0.7)
			(end 1.45 -0.7)
			(stroke
				(width 0.12)
				(type solid)
			)
			(layer "F.SilkS")
		)
		(fp_line
			(start -1.3 -0.7)
			(end -1.45 -0.7)
			(stroke
				(width 0.12)
				(type solid)
			)
			(layer "F.SilkS")
		)
		(fp_line
			(start -1.45 -0.7)
			(end -1.45 -0.4)
			(stroke
				(width 0.12)
				(type solid)
			)
			(layer "F.SilkS")
		)
		(fp_line
			(start 1.45 0.7)
			(end 1.45 0.4)
			(stroke
				(width 0.12)
				(type solid)
			)
			(layer "F.SilkS")
		)
		(fp_line
			(start 1.3 0.7)
			(end 1.45 0.7)
			(stroke
				(width 0.12)
				(type solid)
			)
			(layer "F.SilkS")
		)
		(fp_line
			(start -1.45 0.7)
			(end -1.45 0.4)
			(stroke
				(width 0.12)
				(type solid)
			)
			(layer "F.SilkS")
		)
		(fp_rect
			(start -1.55 -1.85)
			(end 1.55 1.75)
			(stroke
				(width 0.05)
				(type solid)
			)
			(fill no)
			(layer "F.CrtYd")
		)
		(fp_line
			(start 1.5 -0.7)
			(end 1.5 0.7)
			(stroke
				(width 0.1)
				(type solid)
			)
			(layer "F.Fab")
		)
		(fp_line
			(start -1.5 -0.7)
			(end 1.5 -0.7)
			(stroke
				(width 0.1)
				(type solid)
			)
			(layer "F.Fab")
		)
		(fp_line
			(start 1.5 0.7)
			(end -1.5 0.7)
			(stroke
				(width 0.1)
				(type solid)
			)
			(layer "F.Fab")
		)
		(fp_line
			(start -1.5 0.7)
			(end -1.5 -0.7)
			(stroke
				(width 0.1)
				(type solid)
			)
			(layer "F.Fab")
		)
		(fp_text user "."
			(at -1.4 1.2 270)
			(layer "F.SilkS")
			(effects
				(font
					(size 1 1)
					(thickness 0.15)
				)
			)
		)
		(pad "1" smd roundrect
			(at -0.954 1.1 90)
			(size 0.55 1)
			(layers "F.Cu" "F.Mask" "F.Paste")
			(roundrect_rratio 0.15)
			(net 956 "/DC-DC Converters/POE_DC")
			(pinfunction "IN")
			(pintype "power_in")
		)
		(pad "2" smd roundrect
			(at -0.003 1.1 90)
			(size 0.55 1)
			(layers "F.Cu" "F.Mask" "F.Paste")
			(roundrect_rratio 0.15)
			(net 1 "GND")
			(pinfunction "GND")
			(pintype "power_in")
		)
		(pad "3" smd roundrect
			(at 0.947 1.1 90)
			(size 0.55 1)
			(layers "F.Cu" "F.Mask" "F.Paste")
			(roundrect_rratio 0.15)
			(net 1 "GND")
			(pinfunction "CTL")
			(pintype "input")
		)
		(pad "4" smd roundrect
			(at 0.947 -1.214 90)
			(size 0.55 1)
			(layers "F.Cu" "F.Mask" "F.Paste")
			(roundrect_rratio 0.15)
			(net 1158 "unconnected-(U11-STAT-Pad4)")
			(pinfunction "STAT")
			(pintype "output+no_connect")
		)
		(pad "5" smd roundrect
			(at -0.003 -1.214 90)
			(size 0.55 1)
			(layers "F.Cu" "F.Mask" "F.Paste")
			(roundrect_rratio 0.15)
			(net 342 "Net-(Q7-G)")
			(pinfunction "GATE")
			(pintype "output")
		)
		(pad "6" smd roundrect
			(at -0.954 -1.214 90)
			(size 0.55 1)
			(layers "F.Cu" "F.Mask" "F.Paste")
			(roundrect_rratio 0.15)
			(net 702 "VDC")
			(pinfunction "SENSE")
			(pintype "input")
		)
	)
	(footprint "antmicro-footprints:SW_KMR211NGLFS_SMD"
		(layer "F.Cu")
		(at 260.5 186.5 90)
		(property "Reference" "S6"
			(at 1.05 2.65 90)
			(layer "F.SilkS")
			(effects
				(font
					(size 0.7 0.7)
					(thickness 0.15)
				)
				(justify left bottom)
			)
		)
		(property "Value" "SW_KMR211NGLFS_SMD"
			(at -3 3 90)
			(layer "F.Fab")
			(effects
				(font
					(size 0.7 0.7)
					(thickness 0.15)
				)
				(justify left bottom)
			)
		)
		(property "Description" "Tactile Switch, KMR 2 Series, Top Actuated, Surface Mount, Oval Button, 120 gf, 50mA at 32VDC"
			(at 0 0 90)
			(layer "F.Fab")
			(hide yes)
			(effects
				(font
					(size 1.27 1.27)
					(thickness 0.15)
				)
			)
		)
		(property "Author" "Antmicro"
			(at 447 -74 0)
			(layer "F.Fab")
			(hide yes)
			(effects
				(font
					(size 1 1)
					(thickness 0.15)
				)
			)
		)
		(property "License" "Apache-2.0"
			(at 447 -74 0)
			(layer "F.Fab")
			(hide yes)
			(effects
				(font
					(size 1 1)
					(thickness 0.15)
				)
			)
		)
		(property "MPN" "KMR211NGLFS"
			(at 447 -74 0)
			(layer "F.Fab")
			(hide yes)
			(effects
				(font
					(size 1 1)
					(thickness 0.15)
				)
			)
		)
		(property "Manufacturer" "C&K"
			(at 447 -74 0)
			(layer "F.Fab")
			(hide yes)
			(effects
				(font
					(size 1 1)
					(thickness 0.15)
				)
			)
		)
		(sheetname "DC-DC Converters")
		(sheetfile "dc-dc.kicad_sch")
		(attr smd)
		(fp_line
			(start 2.101 -1.6)
			(end -2.1 -1.6)
			(stroke
				(width 0.15)
				(type solid)
			)
			(layer "F.SilkS")
		)
		(fp_line
			(start -2.1 -1.6)
			(end -2.1 -1.499)
			(stroke
				(width 0.15)
				(type solid)
			)
			(layer "F.SilkS")
		)
		(fp_line
			(start 2.101 -1.58)
			(end 2.101 -1.459)
			(stroke
				(width 0.15)
				(type solid)
			)
			(layer "F.SilkS")
		)
		(fp_line
			(start 2.101 1.601)
			(end 2.101 1.48)
			(stroke
				(width 0.15)
				(type solid)
			)
			(layer "F.SilkS")
		)
		(fp_line
			(start 2.101 1.601)
			(end -2.1 1.601)
			(stroke
				(width 0.15)
				(type solid)
			)
			(layer "F.SilkS")
		)
		(fp_line
			(start -2.1 1.601)
			(end -2.1 1.48)
			(stroke
				(width 0.15)
				(type solid)
			)
			(layer "F.SilkS")
		)
		(fp_rect
			(start 2.751 1.75)
			(end -2.748 -1.749)
			(stroke
				(width 0.05)
				(type solid)
			)
			(fill no)
			(layer "F.CrtYd")
		)
		(fp_line
			(start 2.101 -1.6)
			(end -2.1 -1.6)
			(stroke
				(width 0.15)
				(type solid)
			)
			(layer "F.Fab")
		)
		(fp_line
			(start -2.1 -1.6)
			(end -2.1 1.601)
			(stroke
				(width 0.15)
				(type solid)
			)
			(layer "F.Fab")
		)
		(fp_line
			(start -0.248 -0.8)
			(end 0.25 -0.8)
			(stroke
				(width 0.15)
				(type solid)
			)
			(layer "F.Fab")
		)
		(fp_line
			(start 0.25 0.802)
			(end -0.248 0.802)
			(stroke
				(width 0.15)
				(type solid)
			)
			(layer "F.Fab")
		)
		(fp_line
			(start 2.101 1.601)
			(end 2.101 -1.6)
			(stroke
				(width 0.15)
				(type solid)
			)
			(layer "F.Fab")
		)
		(fp_line
			(start -2.1 1.601)
			(end 2.101 1.601)
			(stroke
				(width 0.15)
				(type solid)
			)
			(layer "F.Fab")
		)
		(fp_arc
			(start 0.25 -0.8)
			(mid 1.051001 0.001)
			(end 0.25 0.802)
			(stroke
				(width 0.15)
				(type solid)
			)
			(layer "F.Fab")
		)
		(fp_arc
			(start -0.248 0.802)
			(mid -1.050001 0.001)
			(end -0.248 -0.8)
			(stroke
				(width 0.15)
				(type solid)
			)
			(layer "F.Fab")
		)
		(pad "1" smd rect
			(at -2.048 -0.8 270)
			(size 0.9 1)
			(layers "F.Cu" "F.Mask" "F.Paste")
			(net 1 "GND")
			(pinfunction "1")
			(pintype "passive")
		)
		(pad "2" smd rect
			(at 2.05 -0.8 270)
			(size 0.9 1)
			(layers "F.Cu" "F.Mask" "F.Paste")
			(net 1 "GND")
			(pinfunction "2")
			(pintype "passive")
		)
		(pad "3" smd rect
			(at -2.048 0.802 270)
			(size 0.9 1)
			(layers "F.Cu" "F.Mask" "F.Paste")
			(net 974 "/DC-DC Converters/~{PB_CTRL_IN}")
			(pinfunction "3")
			(pintype "passive")
		)
		(pad "4" smd rect
			(at 2.05 0.802 270)
			(size 0.9 1)
			(layers "F.Cu" "F.Mask" "F.Paste")
			(net 974 "/DC-DC Converters/~{PB_CTRL_IN}")
			(pinfunction "4")
			(pintype "passive")
		)
	)
)
